(kicad_pcb
	(version 20260206)
	(generator "pcbnew")
	(generator_version "10.0")
	(general
		(thickness 1.6)
		(legacy_teardrops no)
	)
	(paper "A4")
	(title_block
		(title "01162023_DA0F0TEBIF0_F0T_Expander_BD_F_brd_V02_OCP.brd")
		(comment 1 "Grand Teton / footprints 6850-6855 of 9728")
	)
	(layers
		(0 "F.Cu" signal "TOP")
		(4 "In1.Cu" signal "GND")
		(6 "In2.Cu" signal "VCC")
		(8 "In3.Cu" signal "VCC1")
		(10 "In4.Cu" signal "GND1")
		(12 "In5.Cu" signal "IN1")
		(14 "In6.Cu" signal "GND2")
		(16 "In7.Cu" signal "IN2")
		(18 "In8.Cu" signal "GND3")
		(20 "In9.Cu" signal "IN3")
		(22 "In10.Cu" signal "GND4")
		(24 "In11.Cu" signal "IN4")
		(26 "In12.Cu" signal "GND5")
		(28 "In13.Cu" signal "IN5")
		(30 "In14.Cu" signal "GND6")
		(32 "In15.Cu" signal "IN6")
		(34 "In16.Cu" signal "GND7")
		(2 "B.Cu" signal "BOTTOM")
		(9 "F.Adhes" user "F.Adhesive")
		(11 "B.Adhes" user "B.Adhesive")
		(13 "F.Paste" user "Package Geometry/Pastemask Top")
		(15 "B.Paste" user "Package Geometry/Pastemask Bottom")
		(5 "F.SilkS" user "Ref Des/Silkscreen Top")
		(7 "B.SilkS" user "Ref Des/Silkscreen Bottom")
		(1 "F.Mask" user "Board Geometry/Soldermask Top")
		(3 "B.Mask" user "Board Geometry/Soldermask Bottom")
		(17 "Dwgs.User" user "User.Drawings")
		(19 "Cmts.User" user "User.Comments")
		(21 "Eco1.User" user "User.Eco1")
		(23 "Eco2.User" user "User.Eco2")
		(25 "Edge.Cuts" user "Board Geometry/Outline")
		(27 "Margin" user)
		(31 "F.CrtYd" user "Package Geometry/Place Bound Top")
		(29 "B.CrtYd" user "Package Geometry/Place Bound Bottom")
		(35 "F.Fab" user "Ref Des/Assembly Top")
		(33 "B.Fab" user "Ref Des/Assembly Bottom")
	)
	(footprint ""
		(layer "F.Cu")
		(at 307.856382 -17.419574 180)
		(property "Reference" "R1702"
			(at 0 0 180)
			(layer "F.SilkS")
			(hide yes)
			(effects
				(font
					(size 1.27 1.27)
				)
			)
		)
		(property "Value" ""
			(at 0 0 180)
			(layer "F.Fab")
			(effects
				(font
					(size 1.27 1.27)
				)
			)
		)
		(duplicate_pad_numbers_are_jumpers no)
		(fp_line
			(start 0.7874 0.4064)
			(end -0.7874 0.4064)
			(stroke
				(width 0.1524)
				(type default)
			)
			(layer "F.SilkS")
		)
		(fp_line
			(start 0.7874 -0.4064)
			(end 0.7874 0.4064)
			(stroke
				(width 0.1524)
				(type default)
			)
			(layer "F.SilkS")
		)
		(fp_line
			(start -0.7874 0.4064)
			(end -0.7874 -0.4064)
			(stroke
				(width 0.1524)
				(type default)
			)
			(layer "F.SilkS")
		)
		(fp_line
			(start -0.7874 -0.4064)
			(end 0.7874 -0.4064)
			(stroke
				(width 0.1524)
				(type default)
			)
			(layer "F.SilkS")
		)
		(fp_line
			(start 0.67945 0.3048)
			(end 0.120396 0.3048)
			(stroke
				(width 0.1)
				(type default)
			)
			(layer "F.Fab")
		)
		(fp_line
			(start 0.67945 -0.3048)
			(end 0.67945 0.3048)
			(stroke
				(width 0.1)
				(type default)
			)
			(layer "F.Fab")
		)
		(fp_line
			(start 0.12065 -0.2794)
			(end 0.12065 -0.3048)
			(stroke
				(width 0.1)
				(type default)
			)
			(layer "F.Fab")
		)
		(fp_line
			(start 0.12065 -0.3048)
			(end 0.67945 -0.3048)
			(stroke
				(width 0.1)
				(type default)
			)
			(layer "F.Fab")
		)
		(fp_line
			(start 0.120396 0.3048)
			(end 0.120396 0.2794)
			(stroke
				(width 0.1)
				(type default)
			)
			(layer "F.Fab")
		)
		(fp_line
			(start 0.120396 0.2794)
			(end -0.12065 0.2794)
			(stroke
				(width 0.1)
				(type default)
			)
			(layer "F.Fab")
		)
		(fp_line
			(start -0.12065 0.3048)
			(end -0.67945 0.3048)
			(stroke
				(width 0.1)
				(type default)
			)
			(layer "F.Fab")
		)
		(fp_line
			(start -0.12065 0.2794)
			(end -0.12065 0.3048)
			(stroke
				(width 0.1)
				(type default)
			)
			(layer "F.Fab")
		)
		(fp_line
			(start -0.12065 -0.2794)
			(end 0.12065 -0.2794)
			(stroke
				(width 0.1)
				(type default)
			)
			(layer "F.Fab")
		)
		(fp_line
			(start -0.12065 -0.305054)
			(end -0.12065 -0.2794)
			(stroke
				(width 0.1)
				(type default)
			)
			(layer "F.Fab")
		)
		(fp_line
			(start -0.67945 0.3048)
			(end -0.67945 -0.305054)
			(stroke
				(width 0.1)
				(type default)
			)
			(layer "F.Fab")
		)
		(fp_line
			(start -0.67945 -0.305054)
			(end -0.12065 -0.305054)
			(stroke
				(width 0.1)
				(type default)
			)
			(layer "F.Fab")
		)
		(pad "1" smd circle
			(at -0.40005 0 180)
			(size 0 0)
			(layers "F.Cu" "F.Mask" "F.Paste")
			(net "P3V3_SSD10")
		)
		(pad "2" smd circle
			(at 0.40005 0 180)
			(size 0 0)
			(layers "F.Cu" "F.Mask" "F.Paste")
			(net "SMB_ISO_SSD10_SCL")
		)
	)
	(footprint ""
		(layer "F.Cu")
		(at 17.911826 -146.263614 180)
		(property "Reference" "C410"
			(at 0 0 180)
			(layer "F.SilkS")
			(hide yes)
			(effects
				(font
					(size 1.27 1.27)
				)
			)
		)
		(property "Value" ""
			(at 0 0 180)
			(layer "F.Fab")
			(effects
				(font
					(size 1.27 1.27)
				)
			)
		)
		(duplicate_pad_numbers_are_jumpers no)
		(fp_line
			(start 0.7874 0.4064)
			(end -0.7874 0.4064)
			(stroke
				(width 0.1524)
				(type default)
			)
			(layer "F.SilkS")
		)
		(fp_line
			(start 0.7874 -0.4064)
			(end 0.7874 0.4064)
			(stroke
				(width 0.1524)
				(type default)
			)
			(layer "F.SilkS")
		)
		(fp_line
			(start -0.7874 0.4064)
			(end -0.7874 -0.4064)
			(stroke
				(width 0.1524)
				(type default)
			)
			(layer "F.SilkS")
		)
		(fp_line
			(start -0.7874 -0.4064)
			(end 0.7874 -0.4064)
			(stroke
				(width 0.1524)
				(type default)
			)
			(layer "F.SilkS")
		)
		(fp_line
			(start 0.67945 0.3048)
			(end 0.120396 0.3048)
			(stroke
				(width 0.1)
				(type default)
			)
			(layer "F.Fab")
		)
		(fp_line
			(start 0.67945 -0.3048)
			(end 0.67945 0.3048)
			(stroke
				(width 0.1)
				(type default)
			)
			(layer "F.Fab")
		)
		(fp_line
			(start 0.12065 -0.2794)
			(end 0.12065 -0.3048)
			(stroke
				(width 0.1)
				(type default)
			)
			(layer "F.Fab")
		)
		(fp_line
			(start 0.12065 -0.3048)
			(end 0.67945 -0.3048)
			(stroke
				(width 0.1)
				(type default)
			)
			(layer "F.Fab")
		)
		(fp_line
			(start 0.120396 0.3048)
			(end 0.120396 0.2794)
			(stroke
				(width 0.1)
				(type default)
			)
			(layer "F.Fab")
		)
		(fp_line
			(start 0.120396 0.2794)
			(end -0.12065 0.2794)
			(stroke
				(width 0.1)
				(type default)
			)
			(layer "F.Fab")
		)
		(fp_line
			(start -0.12065 0.3048)
			(end -0.67945 0.3048)
			(stroke
				(width 0.1)
				(type default)
			)
			(layer "F.Fab")
		)
		(fp_line
			(start -0.12065 0.2794)
			(end -0.12065 0.3048)
			(stroke
				(width 0.1)
				(type default)
			)
			(layer "F.Fab")
		)
		(fp_line
			(start -0.12065 -0.2794)
			(end 0.12065 -0.2794)
			(stroke
				(width 0.1)
				(type default)
			)
			(layer "F.Fab")
		)
		(fp_line
			(start -0.12065 -0.305054)
			(end -0.12065 -0.2794)
			(stroke
				(width 0.1)
				(type default)
			)
			(layer "F.Fab")
		)
		(fp_line
			(start -0.67945 0.3048)
			(end -0.67945 -0.305054)
			(stroke
				(width 0.1)
				(type default)
			)
			(layer "F.Fab")
		)
		(fp_line
			(start -0.67945 -0.305054)
			(end -0.12065 -0.305054)
			(stroke
				(width 0.1)
				(type default)
			)
			(layer "F.Fab")
		)
		(pad "1" smd circle
			(at -0.40005 0 180)
			(size 0 0)
			(layers "F.Cu" "F.Mask" "F.Paste")
			(net "P12V_NIC0_R")
		)
		(pad "2" smd circle
			(at 0.40005 0 180)
			(size 0 0)
			(layers "F.Cu" "F.Mask" "F.Paste")
			(net "GND")
		)
	)
	(footprint ""
		(layer "F.Cu")
		(at 304.325274 -42.849038 180)
		(property "Reference" "R623"
			(at 0 0 180)
			(layer "F.SilkS")
			(hide yes)
			(effects
				(font
					(size 1.27 1.27)
				)
			)
		)
		(property "Value" ""
			(at 0 0 180)
			(layer "F.Fab")
			(effects
				(font
					(size 1.27 1.27)
				)
			)
		)
		(duplicate_pad_numbers_are_jumpers no)
		(fp_line
			(start 0.7874 0.4064)
			(end -0.7874 0.4064)
			(stroke
				(width 0.1524)
				(type default)
			)
			(layer "F.SilkS")
		)
		(fp_line
			(start 0.7874 -0.4064)
			(end 0.7874 0.4064)
			(stroke
				(width 0.1524)
				(type default)
			)
			(layer "F.SilkS")
		)
		(fp_line
			(start -0.7874 0.4064)
			(end -0.7874 -0.4064)
			(stroke
				(width 0.1524)
				(type default)
			)
			(layer "F.SilkS")
		)
		(fp_line
			(start -0.7874 -0.4064)
			(end 0.7874 -0.4064)
			(stroke
				(width 0.1524)
				(type default)
			)
			(layer "F.SilkS")
		)
		(fp_line
			(start 0.67945 0.3048)
			(end 0.120396 0.3048)
			(stroke
				(width 0.1)
				(type default)
			)
			(layer "F.Fab")
		)
		(fp_line
			(start 0.67945 -0.3048)
			(end 0.67945 0.3048)
			(stroke
				(width 0.1)
				(type default)
			)
			(layer "F.Fab")
		)
		(fp_line
			(start 0.12065 -0.2794)
			(end 0.12065 -0.3048)
			(stroke
				(width 0.1)
				(type default)
			)
			(layer "F.Fab")
		)
		(fp_line
			(start 0.12065 -0.3048)
			(end 0.67945 -0.3048)
			(stroke
				(width 0.1)
				(type default)
			)
			(layer "F.Fab")
		)
		(fp_line
			(start 0.120396 0.3048)
			(end 0.120396 0.2794)
			(stroke
				(width 0.1)
				(type default)
			)
			(layer "F.Fab")
		)
		(fp_line
			(start 0.120396 0.2794)
			(end -0.12065 0.2794)
			(stroke
				(width 0.1)
				(type default)
			)
			(layer "F.Fab")
		)
		(fp_line
			(start -0.12065 0.3048)
			(end -0.67945 0.3048)
			(stroke
				(width 0.1)
				(type default)
			)
			(layer "F.Fab")
		)
		(fp_line
			(start -0.12065 0.2794)
			(end -0.12065 0.3048)
			(stroke
				(width 0.1)
				(type default)
			)
			(layer "F.Fab")
		)
		(fp_line
			(start -0.12065 -0.2794)
			(end 0.12065 -0.2794)
			(stroke
				(width 0.1)
				(type default)
			)
			(layer "F.Fab")
		)
		(fp_line
			(start -0.12065 -0.305054)
			(end -0.12065 -0.2794)
			(stroke
				(width 0.1)
				(type default)
			)
			(layer "F.Fab")
		)
		(fp_line
			(start -0.67945 0.3048)
			(end -0.67945 -0.305054)
			(stroke
				(width 0.1)
				(type default)
			)
			(layer "F.Fab")
		)
		(fp_line
			(start -0.67945 -0.305054)
			(end -0.12065 -0.305054)
			(stroke
				(width 0.1)
				(type default)
			)
			(layer "F.Fab")
		)
		(pad "1" smd circle
			(at -0.40005 0 180)
			(size 0 0)
			(layers "F.Cu" "F.Mask" "F.Paste")
			(net "P12V_SSD10_R")
		)
		(pad "2" smd circle
			(at 0.40005 0 180)
			(size 0 0)
			(layers "F.Cu" "F.Mask" "F.Paste")
			(net "P12V_SSD10_VIN_P")
		)
	)
	(footprint ""
		(layer "F.Cu")
		(at 196.224398 -84.476336 180)
		(property "Reference" "U26"
			(at -2.862072 -0.249936 90)
			(unlocked yes)
			(layer "F.SilkS")
			(effects
				(font
					(size 0.7874 0.5842)
					(thickness 0.1524)
				)
				(justify left)
			)
		)
		(property "Value" ""
			(at 0 0 180)
			(layer "F.Fab")
			(effects
				(font
					(size 1.27 1.27)
				)
			)
		)
		(duplicate_pad_numbers_are_jumpers no)
		(fp_line
			(start 2.0574 1.651)
			(end -2.0574 1.651)
			(stroke
				(width 0.1524)
				(type default)
			)
			(layer "F.SilkS")
		)
		(fp_line
			(start 2.0574 -1.651)
			(end 2.0574 1.651)
			(stroke
				(width 0.1524)
				(type default)
			)
			(layer "F.SilkS")
		)
		(fp_line
			(start 0.381 -1.651)
			(end 2.0574 -1.651)
			(stroke
				(width 0.1524)
				(type default)
			)
			(layer "F.SilkS")
		)
		(fp_line
			(start 0 -1.016)
			(end 0.381 -1.651)
			(stroke
				(width 0.1524)
				(type default)
			)
			(layer "F.SilkS")
		)
		(fp_line
			(start -0.381 -1.651)
			(end 0 -1.016)
			(stroke
				(width 0.1524)
				(type default)
			)
			(layer "F.SilkS")
		)
		(fp_line
			(start -2.0574 1.651)
			(end -2.0574 -1.651)
			(stroke
				(width 0.1524)
				(type default)
			)
			(layer "F.SilkS")
		)
		(fp_line
			(start -2.0574 -1.651)
			(end -0.381 -1.651)
			(stroke
				(width 0.1524)
				(type default)
			)
			(layer "F.SilkS")
		)
		(fp_poly
			(pts
				(xy -2.71272 -0.719328) (xy -2.71272 -1.344168) (xy -2.159 -1.016)
			)
			(stroke
				(width 0)
				(type default)
			)
			(fill yes)
			(layer "F.SilkS")
		)
		(fp_line
			(start 1.599946 1.199896)
			(end 0.899922 1.199896)
			(stroke
				(width 0.1)
				(type default)
			)
			(layer "F.Fab")
		)
		(fp_line
			(start 1.599946 -1.199896)
			(end 1.599946 1.199896)
			(stroke
				(width 0.1)
				(type default)
			)
			(layer "F.Fab")
		)
		(fp_line
			(start 0.899922 1.549908)
			(end -0.899922 1.549908)
			(stroke
				(width 0.1)
				(type default)
			)
			(layer "F.Fab")
		)
		(fp_line
			(start 0.899922 1.199896)
			(end 0.899922 1.549908)
			(stroke
				(width 0.1)
				(type default)
			)
			(layer "F.Fab")
		)
		(fp_line
			(start 0.899922 -1.199896)
			(end 1.599946 -1.199896)
			(stroke
				(width 0.1)
				(type default)
			)
			(layer "F.Fab")
		)
		(fp_line
			(start 0.899922 -1.549908)
			(end 0.899922 -1.199896)
			(stroke
				(width 0.1)
				(type default)
			)
			(layer "F.Fab")
		)
		(fp_line
			(start -0.899922 1.549908)
			(end -0.899922 1.199896)
			(stroke
				(width 0.1)
				(type default)
			)
			(layer "F.Fab")
		)
		(fp_line
			(start -0.899922 1.199896)
			(end -1.599946 1.199896)
			(stroke
				(width 0.1)
				(type default)
			)
			(layer "F.Fab")
		)
		(fp_line
			(start -0.899922 -1.199896)
			(end -0.899922 -1.549908)
			(stroke
				(width 0.1)
				(type default)
			)
			(layer "F.Fab")
		)
		(fp_line
			(start -0.899922 -1.549908)
			(end 0.899922 -1.549908)
			(stroke
				(width 0.1)
				(type default)
			)
			(layer "F.Fab")
		)
		(fp_line
			(start -1.599946 1.199896)
			(end -1.599946 -1.199896)
			(stroke
				(width 0.1)
				(type default)
			)
			(layer "F.Fab")
		)
		(fp_line
			(start -1.599946 -1.199896)
			(end -0.899922 -1.199896)
			(stroke
				(width 0.1)
				(type default)
			)
			(layer "F.Fab")
		)
		(fp_poly
			(pts
				(xy -2.71272 -0.719328) (xy -2.71272 -1.344168) (xy -2.159 -1.016)
			)
			(stroke
				(width 0)
				(type default)
			)
			(fill yes)
			(layer "F.Fab")
		)
		(pad "1" smd rect
			(at -1.225042 -0.94996 90)
			(size 0.5588 1.3462)
			(layers "F.Cu" "F.Mask" "F.Paste")
			(net "HP_NIC3_PWRGD_R")
		)
		(pad "2" smd rect
			(at -1.225042 0 90)
			(size 0.5588 1.3462)
			(layers "F.Cu" "F.Mask" "F.Paste")
			(net "RST_NIC3_PERST_R_N")
		)
		(pad "3" smd rect
			(at -1.225042 0.94996 90)
			(size 0.5588 1.3462)
			(layers "F.Cu" "F.Mask" "F.Paste")
			(net "GND")
		)
		(pad "4" smd rect
			(at 1.225042 0.94996 90)
			(size 0.5588 1.3462)
			(layers "F.Cu" "F.Mask" "F.Paste")
			(net "RST_HP_NIC3_N")
		)
		(pad "5" smd rect
			(at 1.225042 -0.94996 90)
			(size 0.5588 1.3462)
			(layers "F.Cu" "F.Mask" "F.Paste")
			(net "P3V3_AUX")
		)
	)
	(footprint ""
		(layer "F.Cu")
		(at 295.877742 -114.267742)
		(property "Reference" "R293"
			(at 0 0 0)
			(layer "F.SilkS")
			(hide yes)
			(effects
				(font
					(size 1.27 1.27)
				)
			)
		)
		(property "Value" ""
			(at 0 0 0)
			(layer "F.Fab")
			(effects
				(font
					(size 1.27 1.27)
				)
			)
		)
		(duplicate_pad_numbers_are_jumpers no)
		(fp_line
			(start -0.7874 -0.4064)
			(end 0.7874 -0.4064)
			(stroke
				(width 0.1524)
				(type default)
			)
			(layer "F.SilkS")
		)
		(fp_line
			(start -0.7874 0.4064)
			(end -0.7874 -0.4064)
			(stroke
				(width 0.1524)
				(type default)
			)
			(layer "F.SilkS")
		)
		(fp_line
			(start 0.7874 -0.4064)
			(end 0.7874 0.4064)
			(stroke
				(width 0.1524)
				(type default)
			)
			(layer "F.SilkS")
		)
		(fp_line
			(start 0.7874 0.4064)
			(end -0.7874 0.4064)
			(stroke
				(width 0.1524)
				(type default)
			)
			(layer "F.SilkS")
		)
		(fp_line
			(start -0.67945 -0.305054)
			(end -0.12065 -0.305054)
			(stroke
				(width 0.1)
				(type default)
			)
			(layer "F.Fab")
		)
		(fp_line
			(start -0.67945 0.3048)
			(end -0.67945 -0.305054)
			(stroke
				(width 0.1)
				(type default)
			)
			(layer "F.Fab")
		)
		(fp_line
			(start -0.12065 -0.305054)
			(end -0.12065 -0.2794)
			(stroke
				(width 0.1)
				(type default)
			)
			(layer "F.Fab")
		)
		(fp_line
			(start -0.12065 -0.2794)
			(end 0.12065 -0.2794)
			(stroke
				(width 0.1)
				(type default)
			)
			(layer "F.Fab")
		)
		(fp_line
			(start -0.12065 0.2794)
			(end -0.12065 0.3048)
			(stroke
				(width 0.1)
				(type default)
			)
			(layer "F.Fab")
		)
		(fp_line
			(start -0.12065 0.3048)
			(end -0.67945 0.3048)
			(stroke
				(width 0.1)
				(type default)
			)
			(layer "F.Fab")
		)
		(fp_line
			(start 0.120396 0.2794)
			(end -0.12065 0.2794)
			(stroke
				(width 0.1)
				(type default)
			)
			(layer "F.Fab")
		)
		(fp_line
			(start 0.120396 0.3048)
			(end 0.120396 0.2794)
			(stroke
				(width 0.1)
				(type default)
			)
			(layer "F.Fab")
		)
		(fp_line
			(start 0.12065 -0.3048)
			(end 0.67945 -0.3048)
			(stroke
				(width 0.1)
				(type default)
			)
			(layer "F.Fab")
		)
		(fp_line
			(start 0.12065 -0.2794)
			(end 0.12065 -0.3048)
			(stroke
				(width 0.1)
				(type default)
			)
			(layer "F.Fab")
		)
		(fp_line
			(start 0.67945 -0.3048)
			(end 0.67945 0.3048)
			(stroke
				(width 0.1)
				(type default)
			)
			(layer "F.Fab")
		)
		(fp_line
			(start 0.67945 0.3048)
			(end 0.120396 0.3048)
			(stroke
				(width 0.1)
				(type default)
			)
			(layer "F.Fab")
		)
		(pad "1" smd circle
			(at -0.40005 0)
			(size 0 0)
			(layers "F.Cu" "F.Mask" "F.Paste")
			(net "RST_SMB_NIC5_MUX_ISO_N")
		)
		(pad "2" smd circle
			(at 0.40005 0)
			(size 0 0)
			(layers "F.Cu" "F.Mask" "F.Paste")
			(net "GND")
		)
	)
	(footprint ""
		(layer "F.Cu")
		(at 334.473804 -26.31186 -90)
		(property "Reference" "U411"
			(at -0.10414 -2.433066 90)
			(unlocked yes)
			(layer "F.SilkS")
			(effects
				(font
					(size 0.7874 0.5842)
					(thickness 0.1524)
				)
			)
		)
		(property "Value" ""
			(at 0 0 270)
			(layer "F.Fab")
			(effects
				(font
					(size 1.27 1.27)
				)
			)
		)
		(duplicate_pad_numbers_are_jumpers no)
		(fp_line
			(start -1.949958 1.610106)
			(end -1.949958 -1.610106)
			(stroke
				(width 0.1524)
				(type default)
			)
			(layer "F.SilkS")
		)
		(fp_line
			(start 1.949958 1.610106)
			(end -1.949958 1.610106)
			(stroke
				(width 0.1524)
				(type default)
			)
			(layer "F.SilkS")
		)
		(fp_line
			(start 1.949958 -1.560068)
			(end 1.949958 1.610106)
			(stroke
				(width 0.1524)
				(type default)
			)
			(layer "F.SilkS")
		)
		(fp_line
			(start -1.949958 -1.610106)
			(end 1.949958 -1.610106)
			(stroke
				(width 0.1524)
				(type default)
			)
			(layer "F.SilkS")
		)
		(fp_line
			(start -0.750062 1.560068)
			(end -0.750062 -1.560068)
			(stroke
				(width 0.1)
				(type default)
			)
			(layer "F.Fab")
		)
		(fp_line
			(start 0.750062 1.560068)
			(end -0.750062 1.560068)
			(stroke
				(width 0.1)
				(type default)
			)
			(layer "F.Fab")
		)
		(fp_line
			(start -0.750062 -1.560068)
			(end 0.750062 -1.560068)
			(stroke
				(width 0.1)
				(type default)
			)
			(layer "F.Fab")
		)
		(fp_line
			(start 0.750062 -1.560068)
			(end 0.750062 1.560068)
			(stroke
				(width 0.1)
				(type default)
			)
			(layer "F.Fab")
		)
		(pad "D" smd rect
			(at 1.100074 0 180)
			(size 1.016 1.4224)
			(layers "F.Cu" "F.Mask" "F.Paste")
			(net "SSD11_LED_ISO_N")
		)
		(pad "G" smd rect
			(at -1.100074 -0.94996 180)
			(size 1.016 1.4224)
			(layers "F.Cu" "F.Mask" "F.Paste")
			(net "SSD11_LED_R")
		)
		(pad "S" smd rect
			(at -1.100074 0.94996 180)
			(size 1.016 1.4224)
			(layers "F.Cu" "F.Mask" "F.Paste")
			(net "GND")
		)
	)
)
